# T6G (Grand Teton) — schematic netlist excerpt (pin names and nets, part order shuffled) for the footprints in the layout excerpt that follows; sources: Cadence DE-HDL packaged netlist, KiCad conversion of 04192023_DAF0TMB3IC0_F0TG_MB_C_brd_V02_OCP.brd

PC631  Q_CAP  0.22UF 16V 10% X7R  pkg 0402  page 223 : A = SW_PVDDIO_P1_BOOT3_R ; B = SW_PVDDIO_P1_BOOTR3
PC2263  Q_CAP  22UF 16V 20% X6S  pkg C0805  page 190 : A = SW_P3V3_AUX_FLT ; B = GND
R3288  Q_RES  68K 1% EMPTY  pkg 0402LF  page 111 : A = FM_P2E_SWA ; B = GND

(kicad_pcb
	(version 20260206)
	(generator "pcbnew")
	(generator_version "10.0")
	(general
		(thickness 1.6)
		(legacy_teardrops no)
	)
	(paper "A4")
	(title_block
		(title "04192023_DAF0TMB3IC0_F0TG_MB_C_brd_V02_OCP.brd")
		(comment 1 "Grand Teton / footprints 2766-2768 of 8354")
	)
	(layers
		(0 "F.Cu" signal "TOP")
		(4 "In1.Cu" signal "GND")
		(6 "In2.Cu" signal "IN1")
		(8 "In3.Cu" signal "GND1")
		(10 "In4.Cu" signal "IN2")
		(12 "In5.Cu" signal "GND2")
		(14 "In6.Cu" signal "IN3")
		(16 "In7.Cu" signal "GND3")
		(18 "In8.Cu" signal "VCC")
		(20 "In9.Cu" signal "VCC1")
		(22 "In10.Cu" signal "GND4")
		(24 "In11.Cu" signal "IN4")
		(26 "In12.Cu" signal "GND5")
		(28 "In13.Cu" signal "IN5")
		(30 "In14.Cu" signal "GND6")
		(32 "In15.Cu" signal "IN6")
		(34 "In16.Cu" signal "GND7")
		(2 "B.Cu" signal "BOTTOM")
		(9 "F.Adhes" user "F.Adhesive")
		(11 "B.Adhes" user "B.Adhesive")
		(13 "F.Paste" user "Package Geometry/Pastemask Top")
		(15 "B.Paste" user "Package Geometry/Pastemask Bottom")
		(5 "F.SilkS" user "Ref Des/Silkscreen Top")
		(7 "B.SilkS" user "Ref Des/Silkscreen Bottom")
		(1 "F.Mask" user "Board Geometry/Soldermask Top")
		(3 "B.Mask" user "Board Geometry/Soldermask Bottom")
		(17 "Dwgs.User" user "User.Drawings")
		(19 "Cmts.User" user "User.Comments")
		(21 "Eco1.User" user "User.Eco1")
		(23 "Eco2.User" user "User.Eco2")
		(25 "Edge.Cuts" user "Board Geometry/Outline")
		(27 "Margin" user)
		(31 "F.CrtYd" user "Package Geometry/Place Bound Top")
		(29 "B.CrtYd" user "Package Geometry/Place Bound Bottom")
		(35 "F.Fab" user "Ref Des/Assembly Top")
		(33 "B.Fab" user "Ref Des/Assembly Bottom")
	)
	(footprint ""
		(layer "F.Cu")
		(at 36.640262 -419.249098 -90)
		(property "Reference" "R3288"
			(at 0 0 270)
			(layer "F.SilkS")
			(hide yes)
			(effects
				(font
					(size 1.27 1.27)
				)
			)
		)
		(property "Value" ""
			(at 0 0 270)
			(layer "F.Fab")
			(effects
				(font
					(size 1.27 1.27)
				)
			)
		)
		(duplicate_pad_numbers_are_jumpers no)
		(fp_line
			(start -0.7874 0.4064)
			(end -0.7874 -0.4064)
			(stroke
				(width 0.1524)
				(type default)
			)
			(layer "F.SilkS")
		)
		(fp_line
			(start 0.7874 0.4064)
			(end -0.7874 0.4064)
			(stroke
				(width 0.1524)
				(type default)
			)
			(layer "F.SilkS")
		)
		(fp_line
			(start -0.7874 -0.4064)
			(end 0.7874 -0.4064)
			(stroke
				(width 0.1524)
				(type default)
			)
			(layer "F.SilkS")
		)
		(fp_line
			(start 0.7874 -0.4064)
			(end 0.7874 0.4064)
			(stroke
				(width 0.1524)
				(type default)
			)
			(layer "F.SilkS")
		)
		(fp_line
			(start -0.67945 0.3048)
			(end -0.67945 -0.305054)
			(stroke
				(width 0.1)
				(type default)
			)
			(layer "F.Fab")
		)
		(fp_line
			(start -0.12065 0.3048)
			(end -0.67945 0.3048)
			(stroke
				(width 0.1)
				(type default)
			)
			(layer "F.Fab")
		)
		(fp_line
			(start 0.120396 0.3048)
			(end 0.120396 0.2794)
			(stroke
				(width 0.1)
				(type default)
			)
			(layer "F.Fab")
		)
		(fp_line
			(start 0.67945 0.3048)
			(end 0.120396 0.3048)
			(stroke
				(width 0.1)
				(type default)
			)
			(layer "F.Fab")
		)
		(fp_line
			(start -0.12065 0.2794)
			(end -0.12065 0.3048)
			(stroke
				(width 0.1)
				(type default)
			)
			(layer "F.Fab")
		)
		(fp_line
			(start 0.120396 0.2794)
			(end -0.12065 0.2794)
			(stroke
				(width 0.1)
				(type default)
			)
			(layer "F.Fab")
		)
		(fp_line
			(start -0.12065 -0.2794)
			(end 0.12065 -0.2794)
			(stroke
				(width 0.1)
				(type default)
			)
			(layer "F.Fab")
		)
		(fp_line
			(start 0.12065 -0.2794)
			(end 0.12065 -0.3048)
			(stroke
				(width 0.1)
				(type default)
			)
			(layer "F.Fab")
		)
		(fp_line
			(start 0.12065 -0.3048)
			(end 0.67945 -0.3048)
			(stroke
				(width 0.1)
				(type default)
			)
			(layer "F.Fab")
		)
		(fp_line
			(start 0.67945 -0.3048)
			(end 0.67945 0.3048)
			(stroke
				(width 0.1)
				(type default)
			)
			(layer "F.Fab")
		)
		(fp_line
			(start -0.67945 -0.305054)
			(end -0.12065 -0.305054)
			(stroke
				(width 0.1)
				(type default)
			)
			(layer "F.Fab")
		)
		(fp_line
			(start -0.12065 -0.305054)
			(end -0.12065 -0.2794)
			(stroke
				(width 0.1)
				(type default)
			)
			(layer "F.Fab")
		)
		(pad "1" smd circle
			(at -0.40005 0 270)
			(size 0 0)
			(layers "F.Cu" "F.Mask" "F.Paste")
			(net "FM_P2E_SWA")
		)
		(pad "2" smd circle
			(at 0.40005 0 270)
			(size 0 0)
			(layers "F.Cu" "F.Mask" "F.Paste")
			(net "GND")
		)
	)
	(footprint ""
		(layer "F.Cu")
		(at 444.457582 -53.188108 90)
		(property "Reference" "PC2263"
			(at 0 0 90)
			(layer "F.SilkS")
			(hide yes)
			(effects
				(font
					(size 1.27 1.27)
				)
			)
		)
		(property "Value" ""
			(at 0 0 90)
			(layer "F.Fab")
			(effects
				(font
					(size 1.27 1.27)
				)
			)
		)
		(duplicate_pad_numbers_are_jumpers no)
		(fp_line
			(start 1.524 -0.762)
			(end 1.524 0.762)
			(stroke
				(width 0.1524)
				(type default)
			)
			(layer "F.SilkS")
		)
		(fp_line
			(start -1.524 -0.762)
			(end 1.524 -0.762)
			(stroke
				(width 0.1524)
				(type default)
			)
			(layer "F.SilkS")
		)
		(fp_line
			(start 1.524 0.762)
			(end -1.524 0.762)
			(stroke
				(width 0.1524)
				(type default)
			)
			(layer "F.SilkS")
		)
		(fp_line
			(start -1.524 0.762)
			(end -1.524 -0.762)
			(stroke
				(width 0.1524)
				(type default)
			)
			(layer "F.SilkS")
		)
		(fp_line
			(start 1.1049 -0.724916)
			(end -1.1049 -0.724916)
			(stroke
				(width 0.1)
				(type default)
			)
			(layer "F.Fab")
		)
		(fp_line
			(start -1.1049 -0.724916)
			(end -1.1049 0.724916)
			(stroke
				(width 0.1)
				(type default)
			)
			(layer "F.Fab")
		)
		(fp_line
			(start 1.1049 0.724916)
			(end 1.1049 -0.724916)
			(stroke
				(width 0.1)
				(type default)
			)
			(layer "F.Fab")
		)
		(fp_line
			(start -1.1049 0.724916)
			(end 1.1049 0.724916)
			(stroke
				(width 0.1)
				(type default)
			)
			(layer "F.Fab")
		)
		(pad "1" smd rect
			(at -0.889 0 270)
			(size 1.016 1.27)
			(layers "F.Cu" "F.Mask" "F.Paste")
			(net "SW_P3V3_AUX_FLT")
		)
		(pad "2" smd rect
			(at 0.889 0 270)
			(size 1.016 1.27)
			(layers "F.Cu" "F.Mask" "F.Paste")
			(net "GND")
		)
	)
	(footprint ""
		(layer "F.Cu")
		(at 38.666928 -351.372932 -90)
		(property "Reference" "PC631"
			(at 0 0 270)
			(layer "F.SilkS")
			(hide yes)
			(effects
				(font
					(size 1.27 1.27)
				)
			)
		)
		(property "Value" ""
			(at 0 0 270)
			(layer "F.Fab")
			(effects
				(font
					(size 1.27 1.27)
				)
			)
		)
		(duplicate_pad_numbers_are_jumpers no)
		(fp_line
			(start -0.7874 0.4064)
			(end -0.7874 -0.4064)
			(stroke
				(width 0.1524)
				(type default)
			)
			(layer "F.SilkS")
		)
		(fp_line
			(start 0.7874 0.4064)
			(end -0.7874 0.4064)
			(stroke
				(width 0.1524)
				(type default)
			)
			(layer "F.SilkS")
		)
		(fp_line
			(start -0.7874 -0.4064)
			(end 0.7874 -0.4064)
			(stroke
				(width 0.1524)
				(type default)
			)
			(layer "F.SilkS")
		)
		(fp_line
			(start 0.7874 -0.4064)
			(end 0.7874 0.4064)
			(stroke
				(width 0.1524)
				(type default)
			)
			(layer "F.SilkS")
		)
		(fp_line
			(start -0.67945 0.3048)
			(end -0.67945 -0.305054)
			(stroke
				(width 0.1)
				(type default)
			)
			(layer "F.Fab")
		)
		(fp_line
			(start -0.12065 0.3048)
			(end -0.67945 0.3048)
			(stroke
				(width 0.1)
				(type default)
			)
			(layer "F.Fab")
		)
		(fp_line
			(start 0.120396 0.3048)
			(end 0.120396 0.2794)
			(stroke
				(width 0.1)
				(type default)
			)
			(layer "F.Fab")
		)
		(fp_line
			(start 0.67945 0.3048)
			(end 0.120396 0.3048)
			(stroke
				(width 0.1)
				(type default)
			)
			(layer "F.Fab")
		)
		(fp_line
			(start -0.12065 0.2794)
			(end -0.12065 0.3048)
			(stroke
				(width 0.1)
				(type default)
			)
			(layer "F.Fab")
		)
		(fp_line
			(start 0.120396 0.2794)
			(end -0.12065 0.2794)
			(stroke
				(width 0.1)
				(type default)
			)
			(layer "F.Fab")
		)
		(fp_line
			(start -0.12065 -0.2794)
			(end 0.12065 -0.2794)
			(stroke
				(width 0.1)
				(type default)
			)
			(layer "F.Fab")
		)
		(fp_line
			(start 0.12065 -0.2794)
			(end 0.12065 -0.3048)
			(stroke
				(width 0.1)
				(type default)
			)
			(layer "F.Fab")
		)
		(fp_line
			(start 0.12065 -0.3048)
			(end 0.67945 -0.3048)
			(stroke
				(width 0.1)
				(type default)
			)
			(layer "F.Fab")
		)
		(fp_line
			(start 0.67945 -0.3048)
			(end 0.67945 0.3048)
			(stroke
				(width 0.1)
				(type default)
			)
			(layer "F.Fab")
		)
		(fp_line
			(start -0.67945 -0.305054)
			(end -0.12065 -0.305054)
			(stroke
				(width 0.1)
				(type default)
			)
			(layer "F.Fab")
		)
		(fp_line
			(start -0.12065 -0.305054)
			(end -0.12065 -0.2794)
			(stroke
				(width 0.1)
				(type default)
			)
			(layer "F.Fab")
		)
		(pad "1" smd circle
			(at -0.40005 0 270)
			(size 0 0)
			(layers "F.Cu" "F.Mask" "F.Paste")
			(net "SW_PVDDIO_P1_BOOT3_R")
		)
		(pad "2" smd circle
			(at 0.40005 0 270)
			(size 0 0)
			(layers "F.Cu" "F.Mask" "F.Paste")
			(net "SW_PVDDIO_P1_BOOTR3")
		)
	)
)
